(kicad_pcb
	(version 20260206)
	(generator "pcbnew")
	(generator_version "10.0")
	(general
		(thickness 1.6)
		(legacy_teardrops no)
	)
	(paper "A4")
	(title_block
		(title "Wiwynn_Tioga_Pass_MB.brd")
		(comment 1 "Tioga Pass / footprint 313 of 4770 (EU4D5), pads 1-41 of 41")
	)
	(layers
		(0 "F.Cu" signal "TOP")
		(4 "In1.Cu" signal "L2GND")
		(6 "In2.Cu" signal "L3")
		(8 "In3.Cu" signal "L4GND")
		(10 "In4.Cu" signal "L5")
		(12 "In5.Cu" signal "L6GND")
		(14 "In6.Cu" signal "L7VCC")
		(16 "In7.Cu" signal "L8VCC")
		(18 "In8.Cu" signal "L9GND")
		(20 "In9.Cu" signal "L10")
		(22 "In10.Cu" signal "L11GND")
		(24 "In11.Cu" signal "L12")
		(26 "In12.Cu" signal "L13GND")
		(2 "B.Cu" signal "BOTTOM")
		(9 "F.Adhes" user "F.Adhesive")
		(11 "B.Adhes" user "B.Adhesive")
		(13 "F.Paste" user "Package Geometry/Pastemask Top")
		(15 "B.Paste" user "Package Geometry/Pastemask Bottom")
		(5 "F.SilkS" user "Ref Des/Silkscreen Top")
		(7 "B.SilkS" user "Ref Des/Silkscreen Bottom")
		(1 "F.Mask" user "Board Geometry/Soldermask Top")
		(3 "B.Mask" user "Board Geometry/Soldermask Bottom")
		(17 "Dwgs.User" user "User.Drawings")
		(19 "Cmts.User" user "User.Comments")
		(21 "Eco1.User" user "User.Eco1")
		(23 "Eco2.User" user "User.Eco2")
		(25 "Edge.Cuts" user "Board Geometry/Outline")
		(27 "Margin" user)
		(31 "F.CrtYd" user "Package Geometry/Place Bound Top")
		(29 "B.CrtYd" user "Package Geometry/Place Bound Bottom")
		(35 "F.Fab" user "Ref Des/Assembly Top")
		(33 "B.Fab" user "Ref Des/Assembly Bottom")
	)
	(footprint ""
		(layer "F.Cu")
		(at 169.1894 -66.802 -90)
		(property "Reference" "EU4D5"
			(at 0.6096 -3.60807 90)
			(unlocked yes)
			(layer "F.SilkS")
			(effects
				(font
					(size 0.7874 0.5842)
					(thickness 0.1524)
				)
				(justify left)
			)
		)
		(property "Value" ""
			(at 0 0 270)
			(layer "F.Fab")
			(effects
				(font
					(size 1.27 1.27)
				)
			)
		)
		(duplicate_pad_numbers_are_jumpers no)
		(pad "1" smd custom
			(at -2.4511 -1.800098 270)
			(size 0.0508 0.0508)
			(layers "F.Cu" "F.Mask" "F.Paste")
			(net "Net_336")
			(options
				(clearance outline)
				(anchor circle)
			)
			(primitives
				(gr_poly
					(pts
						(arc
							(start 0.254 -0.1016)
							(mid 0.3556 0)
							(end 0.254 0.1016)
						)
						(xy -0.3556 0.1016) (xy -0.3556 -0.1016)
					)
					(width 0)
					(fill yes)
				)
			)
		)
		(pad "2" smd custom
			(at -2.4511 -1.400048 270)
			(size 0.0508 0.0508)
			(layers "F.Cu" "F.Mask" "F.Paste")
			(net "Net_337")
			(options
				(clearance outline)
				(anchor circle)
			)
			(primitives
				(gr_poly
					(pts
						(arc
							(start 0.254 -0.1016)
							(mid 0.3556 0)
							(end 0.254 0.1016)
						)
						(xy -0.3556 0.1016) (xy -0.3556 -0.1016)
					)
					(width 0)
					(fill yes)
				)
			)
		)
		(pad "3" smd custom
			(at -2.4511 -0.999998 270)
			(size 0.0508 0.0508)
			(layers "F.Cu" "F.Mask" "F.Paste")
			(net "Net_279")
			(options
				(clearance outline)
				(anchor circle)
			)
			(primitives
				(gr_poly
					(pts
						(arc
							(start 0.254 -0.1016)
							(mid 0.3556 0)
							(end 0.254 0.1016)
						)
						(xy -0.3556 0.1016) (xy -0.3556 -0.1016)
					)
					(width 0)
					(fill yes)
				)
			)
		)
		(pad "4" smd custom
			(at -2.4511 -0.599948 270)
			(size 0.0508 0.0508)
			(layers "F.Cu" "F.Mask" "F.Paste")
			(net "Net_338")
			(options
				(clearance outline)
				(anchor circle)
			)
			(primitives
				(gr_poly
					(pts
						(arc
							(start 0.254 -0.1016)
							(mid 0.3556 0)
							(end 0.254 0.1016)
						)
						(xy -0.3556 0.1016) (xy -0.3556 -0.1016)
					)
					(width 0)
					(fill yes)
				)
			)
		)
		(pad "5" smd custom
			(at -2.4511 -0.199898 270)
			(size 0.0508 0.0508)
			(layers "F.Cu" "F.Mask" "F.Paste")
			(net "VR_PVCCIO_CPU1_PWM1")
			(options
				(clearance outline)
				(anchor circle)
			)
			(primitives
				(gr_poly
					(pts
						(arc
							(start 0.254 -0.1016)
							(mid 0.3556 0)
							(end 0.254 0.1016)
						)
						(xy -0.3556 0.1016) (xy -0.3556 -0.1016)
					)
					(width 0)
					(fill yes)
				)
			)
		)
		(pad "6" smd custom
			(at -2.4511 0.199898 270)
			(size 0.0508 0.0508)
			(layers "F.Cu" "F.Mask" "F.Paste")
			(net "SMB_VR_STBY_LVC3_SDA")
			(options
				(clearance outline)
				(anchor circle)
			)
			(primitives
				(gr_poly
					(pts
						(arc
							(start 0.254 -0.1016)
							(mid 0.3556 0)
							(end 0.254 0.1016)
						)
						(xy -0.3556 0.1016) (xy -0.3556 -0.1016)
					)
					(width 0)
					(fill yes)
				)
			)
		)
		(pad "7" smd custom
			(at -2.4511 0.599948 270)
			(size 0.0508 0.0508)
			(layers "F.Cu" "F.Mask" "F.Paste")
			(net "SMB_VR_STBY_LVC3_SCL")
			(options
				(clearance outline)
				(anchor circle)
			)
			(primitives
				(gr_poly
					(pts
						(arc
							(start 0.254 -0.1016)
							(mid 0.3556 0)
							(end 0.254 0.1016)
						)
						(xy -0.3556 0.1016) (xy -0.3556 -0.1016)
					)
					(width 0)
					(fill yes)
				)
			)
		)
		(pad "8" smd custom
			(at -2.4511 0.999998 270)
			(size 0.0508 0.0508)
			(layers "F.Cu" "F.Mask" "F.Paste")
			(net "Net_280")
			(options
				(clearance outline)
				(anchor circle)
			)
			(primitives
				(gr_poly
					(pts
						(arc
							(start 0.254 -0.1016)
							(mid 0.3556 0)
							(end 0.254 0.1016)
						)
						(xy -0.3556 0.1016) (xy -0.3556 -0.1016)
					)
					(width 0)
					(fill yes)
				)
			)
		)
		(pad "9" smd custom
			(at -2.4511 1.400048 270)
			(size 0.0508 0.0508)
			(layers "F.Cu" "F.Mask" "F.Paste")
			(net "PWRGD_PVCCIO_CPU1_R")
			(options
				(clearance outline)
				(anchor circle)
			)
			(primitives
				(gr_poly
					(pts
						(arc
							(start 0.254 -0.1016)
							(mid 0.3556 0)
							(end 0.254 0.1016)
						)
						(xy -0.3556 0.1016) (xy -0.3556 -0.1016)
					)
					(width 0)
					(fill yes)
				)
			)
		)
		(pad "10" smd custom
			(at -2.4511 1.800098 270)
			(size 0.0508 0.0508)
			(layers "F.Cu" "F.Mask" "F.Paste")
			(net "VR_PVCCIO_CPU1_EN")
			(options
				(clearance outline)
				(anchor circle)
			)
			(primitives
				(gr_poly
					(pts
						(arc
							(start 0.254 -0.1016)
							(mid 0.3556 0)
							(end 0.254 0.1016)
						)
						(xy -0.3556 0.1016) (xy -0.3556 -0.1016)
					)
					(width 0)
					(fill yes)
				)
			)
		)
		(pad "11" smd custom
			(at -1.800098 2.4511 270)
			(size 0.0508 0.0508)
			(layers "F.Cu" "F.Mask" "F.Paste")
			(net "IRQ_PVCCIO_CPU1_VRHOT_N")
			(options
				(clearance outline)
				(anchor circle)
			)
			(primitives
				(gr_poly
					(pts
						(arc
							(start -0.1016 -0.254)
							(mid 0 -0.3556)
							(end 0.1016 -0.254)
						)
						(xy 0.1016 0.3556) (xy -0.1016 0.3556)
					)
					(width 0)
					(fill yes)
				)
			)
		)
		(pad "12" smd custom
			(at -1.400048 2.4511 270)
			(size 0.0508 0.0508)
			(layers "F.Cu" "F.Mask" "F.Paste")
			(net "Net_264")
			(options
				(clearance outline)
				(anchor circle)
			)
			(primitives
				(gr_poly
					(pts
						(arc
							(start -0.1016 -0.254)
							(mid 0 -0.3556)
							(end 0.1016 -0.254)
						)
						(xy 0.1016 0.3556) (xy -0.1016 0.3556)
					)
					(width 0)
					(fill yes)
				)
			)
		)
		(pad "13" smd custom
			(at -0.999998 2.4511 270)
			(size 0.0508 0.0508)
			(layers "F.Cu" "F.Mask" "F.Paste")
			(net "Net_262")
			(options
				(clearance outline)
				(anchor circle)
			)
			(primitives
				(gr_poly
					(pts
						(arc
							(start -0.1016 -0.254)
							(mid 0 -0.3556)
							(end 0.1016 -0.254)
						)
						(xy 0.1016 0.3556) (xy -0.1016 0.3556)
					)
					(width 0)
					(fill yes)
				)
			)
		)
		(pad "14" smd custom
			(at -0.599948 2.4511 270)
			(size 0.0508 0.0508)
			(layers "F.Cu" "F.Mask" "F.Paste")
			(net "Net_263")
			(options
				(clearance outline)
				(anchor circle)
			)
			(primitives
				(gr_poly
					(pts
						(arc
							(start -0.1016 -0.254)
							(mid 0 -0.3556)
							(end 0.1016 -0.254)
						)
						(xy 0.1016 0.3556) (xy -0.1016 0.3556)
					)
					(width 0)
					(fill yes)
				)
			)
		)
		(pad "15" smd custom
			(at -0.199898 2.4511 270)
			(size 0.0508 0.0508)
			(layers "F.Cu" "F.Mask" "F.Paste")
			(net "SVID_CLK_PVCCIO_CPU1")
			(options
				(clearance outline)
				(anchor circle)
			)
			(primitives
				(gr_poly
					(pts
						(arc
							(start -0.1016 -0.254)
							(mid 0 -0.3556)
							(end 0.1016 -0.254)
						)
						(xy 0.1016 0.3556) (xy -0.1016 0.3556)
					)
					(width 0)
					(fill yes)
				)
			)
		)
		(pad "16" smd custom
			(at 0.199898 2.4511 270)
			(size 0.0508 0.0508)
			(layers "F.Cu" "F.Mask" "F.Paste")
			(net "SVID_VDIO_PVCCIO_CPU1")
			(options
				(clearance outline)
				(anchor circle)
			)
			(primitives
				(gr_poly
					(pts
						(arc
							(start -0.1016 -0.254)
							(mid 0 -0.3556)
							(end 0.1016 -0.254)
						)
						(xy 0.1016 0.3556) (xy -0.1016 0.3556)
					)
					(width 0)
					(fill yes)
				)
			)
		)
		(pad "17" smd custom
			(at 0.599948 2.4511 270)
			(size 0.0508 0.0508)
			(layers "F.Cu" "F.Mask" "F.Paste")
			(net "SVID_ALERT_PVCCIO_CPU1")
			(options
				(clearance outline)
				(anchor circle)
			)
			(primitives
				(gr_poly
					(pts
						(arc
							(start -0.1016 -0.254)
							(mid 0 -0.3556)
							(end 0.1016 -0.254)
						)
						(xy 0.1016 0.3556) (xy -0.1016 0.3556)
					)
					(width 0)
					(fill yes)
				)
			)
		)
		(pad "18" smd custom
			(at 0.999998 2.4511 270)
			(size 0.0508 0.0508)
			(layers "F.Cu" "F.Mask" "F.Paste")
			(net "Net_302")
			(options
				(clearance outline)
				(anchor circle)
			)
			(primitives
				(gr_poly
					(pts
						(arc
							(start -0.1016 -0.254)
							(mid 0 -0.3556)
							(end 0.1016 -0.254)
						)
						(xy 0.1016 0.3556) (xy -0.1016 0.3556)
					)
					(width 0)
					(fill yes)
				)
			)
		)
		(pad "19" smd custom
			(at 1.400048 2.4511 270)
			(size 0.0508 0.0508)
			(layers "F.Cu" "F.Mask" "F.Paste")
			(net "VR_PVCCIO_CPU1_AVSP")
			(options
				(clearance outline)
				(anchor circle)
			)
			(primitives
				(gr_poly
					(pts
						(arc
							(start -0.1016 -0.254)
							(mid 0 -0.3556)
							(end 0.1016 -0.254)
						)
						(xy 0.1016 0.3556) (xy -0.1016 0.3556)
					)
					(width 0)
					(fill yes)
				)
			)
		)
		(pad "20" smd custom
			(at 1.800098 2.4511 270)
			(size 0.0508 0.0508)
			(layers "F.Cu" "F.Mask" "F.Paste")
			(net "VSENSE_PVCCIO_CPU1_AVSN")
			(options
				(clearance outline)
				(anchor circle)
			)
			(primitives
				(gr_poly
					(pts
						(arc
							(start -0.1016 -0.254)
							(mid 0 -0.3556)
							(end 0.1016 -0.254)
						)
						(xy 0.1016 0.3556) (xy -0.1016 0.3556)
					)
					(width 0)
					(fill yes)
				)
			)
		)
		(pad "21" smd custom
			(at 2.4511 1.800098 270)
			(size 0.0508 0.0508)
			(layers "F.Cu" "F.Mask" "F.Paste")
			(net "VR_PVCCIO_CPU1_AIREF1")
			(options
				(clearance outline)
				(anchor circle)
			)
			(primitives
				(gr_poly
					(pts
						(arc
							(start -0.254 0.1016)
							(mid -0.3556 0)
							(end -0.254 -0.1016)
						)
						(xy 0.3556 -0.1016) (xy 0.3556 0.1016)
					)
					(width 0)
					(fill yes)
				)
			)
		)
		(pad "22" smd custom
			(at 2.4511 1.400048 270)
			(size 0.0508 0.0508)
			(layers "F.Cu" "F.Mask" "F.Paste")
			(net "ISENSE_PVCCIO_CPU1_PH1_IMON")
			(options
				(clearance outline)
				(anchor circle)
			)
			(primitives
				(gr_poly
					(pts
						(arc
							(start -0.254 0.1016)
							(mid -0.3556 0)
							(end -0.254 -0.1016)
						)
						(xy 0.3556 -0.1016) (xy 0.3556 0.1016)
					)
					(width 0)
					(fill yes)
				)
			)
		)
		(pad "23" smd custom
			(at 2.4511 0.999998 270)
			(size 0.0508 0.0508)
			(layers "F.Cu" "F.Mask" "F.Paste")
			(net "GND")
			(options
				(clearance outline)
				(anchor circle)
			)
			(primitives
				(gr_poly
					(pts
						(arc
							(start -0.254 0.1016)
							(mid -0.3556 0)
							(end -0.254 -0.1016)
						)
						(xy 0.3556 -0.1016) (xy 0.3556 0.1016)
					)
					(width 0)
					(fill yes)
				)
			)
		)
		(pad "24" smd custom
			(at 2.4511 0.599948 270)
			(size 0.0508 0.0508)
			(layers "F.Cu" "F.Mask" "F.Paste")
			(net "Net_339")
			(options
				(clearance outline)
				(anchor circle)
			)
			(primitives
				(gr_poly
					(pts
						(arc
							(start -0.254 0.1016)
							(mid -0.3556 0)
							(end -0.254 -0.1016)
						)
						(xy 0.3556 -0.1016) (xy 0.3556 0.1016)
					)
					(width 0)
					(fill yes)
				)
			)
		)
		(pad "25" smd custom
			(at 2.4511 0.199898 270)
			(size 0.0508 0.0508)
			(layers "F.Cu" "F.Mask" "F.Paste")
			(net "Net_258")
			(options
				(clearance outline)
				(anchor circle)
			)
			(primitives
				(gr_poly
					(pts
						(arc
							(start -0.254 0.1016)
							(mid -0.3556 0)
							(end -0.254 -0.1016)
						)
						(xy 0.3556 -0.1016) (xy 0.3556 0.1016)
					)
					(width 0)
					(fill yes)
				)
			)
		)
		(pad "26" smd custom
			(at 2.4511 -0.199898 270)
			(size 0.0508 0.0508)
			(layers "F.Cu" "F.Mask" "F.Paste")
			(net "GND")
			(options
				(clearance outline)
				(anchor circle)
			)
			(primitives
				(gr_poly
					(pts
						(arc
							(start -0.254 0.1016)
							(mid -0.3556 0)
							(end -0.254 -0.1016)
						)
						(xy 0.3556 -0.1016) (xy 0.3556 0.1016)
					)
					(width 0)
					(fill yes)
				)
			)
		)
		(pad "27" smd custom
			(at 2.4511 -0.599948 270)
			(size 0.0508 0.0508)
			(layers "F.Cu" "F.Mask" "F.Paste")
			(net "GND")
			(options
				(clearance outline)
				(anchor circle)
			)
			(primitives
				(gr_poly
					(pts
						(arc
							(start -0.254 0.1016)
							(mid -0.3556 0)
							(end -0.254 -0.1016)
						)
						(xy 0.3556 -0.1016) (xy 0.3556 0.1016)
					)
					(width 0)
					(fill yes)
				)
			)
		)
		(pad "28" smd custom
			(at 2.4511 -0.999998 270)
			(size 0.0508 0.0508)
			(layers "F.Cu" "F.Mask" "F.Paste")
			(net "Net_340")
			(options
				(clearance outline)
				(anchor circle)
			)
			(primitives
				(gr_poly
					(pts
						(arc
							(start -0.254 0.1016)
							(mid -0.3556 0)
							(end -0.254 -0.1016)
						)
						(xy 0.3556 -0.1016) (xy 0.3556 0.1016)
					)
					(width 0)
					(fill yes)
				)
			)
		)
		(pad "29" smd custom
			(at 2.4511 -1.400048 270)
			(size 0.0508 0.0508)
			(layers "F.Cu" "F.Mask" "F.Paste")
			(net "Net_261")
			(options
				(clearance outline)
				(anchor circle)
			)
			(primitives
				(gr_poly
					(pts
						(arc
							(start -0.254 0.1016)
							(mid -0.3556 0)
							(end -0.254 -0.1016)
						)
						(xy 0.3556 -0.1016) (xy 0.3556 0.1016)
					)
					(width 0)
					(fill yes)
				)
			)
		)
		(pad "30" smd custom
			(at 2.4511 -1.800098 270)
			(size 0.0508 0.0508)
			(layers "F.Cu" "F.Mask" "F.Paste")
			(net "Net_260")
			(options
				(clearance outline)
				(anchor circle)
			)
			(primitives
				(gr_poly
					(pts
						(arc
							(start -0.254 0.1016)
							(mid -0.3556 0)
							(end -0.254 -0.1016)
						)
						(xy 0.3556 -0.1016) (xy 0.3556 0.1016)
					)
					(width 0)
					(fill yes)
				)
			)
		)
		(pad "31" smd custom
			(at 1.800098 -2.4511 270)
			(size 0.0508 0.0508)
			(layers "F.Cu" "F.Mask" "F.Paste")
			(net "Net_303")
			(options
				(clearance outline)
				(anchor circle)
			)
			(primitives
				(gr_poly
					(pts
						(arc
							(start 0.1016 0.254)
							(mid 0 0.3556)
							(end -0.1016 0.254)
						)
						(xy -0.1016 -0.3556) (xy 0.1016 -0.3556)
					)
					(width 0)
					(fill yes)
				)
			)
		)
		(pad "32" smd custom
			(at 1.400048 -2.4511 270)
			(size 0.0508 0.0508)
			(layers "F.Cu" "F.Mask" "F.Paste")
			(net "PU_VR_PVCCIO_CPU1_FAULT1")
			(options
				(clearance outline)
				(anchor circle)
			)
			(primitives
				(gr_poly
					(pts
						(arc
							(start 0.1016 0.254)
							(mid 0 0.3556)
							(end -0.1016 0.254)
						)
						(xy -0.1016 -0.3556) (xy 0.1016 -0.3556)
					)
					(width 0)
					(fill yes)
				)
			)
		)
		(pad "33" smd custom
			(at 0.999998 -2.4511 270)
			(size 0.0508 0.0508)
			(layers "F.Cu" "F.Mask" "F.Paste")
			(net "VR_PVCCIO_CPU1_XADDR2")
			(options
				(clearance outline)
				(anchor circle)
			)
			(primitives
				(gr_poly
					(pts
						(arc
							(start 0.1016 0.254)
							(mid 0 0.3556)
							(end -0.1016 0.254)
						)
						(xy -0.1016 -0.3556) (xy 0.1016 -0.3556)
					)
					(width 0)
					(fill yes)
				)
			)
		)
		(pad "34" smd custom
			(at 0.599948 -2.4511 270)
			(size 0.0508 0.0508)
			(layers "F.Cu" "F.Mask" "F.Paste")
			(net "Net_259")
			(options
				(clearance outline)
				(anchor circle)
			)
			(primitives
				(gr_poly
					(pts
						(arc
							(start 0.1016 0.254)
							(mid 0 0.3556)
							(end -0.1016 0.254)
						)
						(xy -0.1016 -0.3556) (xy 0.1016 -0.3556)
					)
					(width 0)
					(fill yes)
				)
			)
		)
		(pad "35" smd custom
			(at 0.199898 -2.4511 270)
			(size 0.0508 0.0508)
			(layers "F.Cu" "F.Mask" "F.Paste")
			(net "A_TSENSE_PVCCIO_CPU1")
			(options
				(clearance outline)
				(anchor circle)
			)
			(primitives
				(gr_poly
					(pts
						(arc
							(start 0.1016 0.254)
							(mid 0 0.3556)
							(end -0.1016 0.254)
						)
						(xy -0.1016 -0.3556) (xy 0.1016 -0.3556)
					)
					(width 0)
					(fill yes)
				)
			)
		)
		(pad "36" smd custom
			(at -0.199898 -2.4511 270)
			(size 0.0508 0.0508)
			(layers "F.Cu" "F.Mask" "F.Paste")
			(net "VR_PVCCIO_CPU1_XADDR1")
			(options
				(clearance outline)
				(anchor circle)
			)
			(primitives
				(gr_poly
					(pts
						(arc
							(start 0.1016 0.254)
							(mid 0 0.3556)
							(end -0.1016 0.254)
						)
						(xy -0.1016 -0.3556) (xy 0.1016 -0.3556)
					)
					(width 0)
					(fill yes)
				)
			)
		)
		(pad "37" smd custom
			(at -0.599948 -2.4511 270)
			(size 0.0508 0.0508)
			(layers "F.Cu" "F.Mask" "F.Paste")
			(net "VR_PVCCIO_CPU1_VINSEN")
			(options
				(clearance outline)
				(anchor circle)
			)
			(primitives
				(gr_poly
					(pts
						(arc
							(start 0.1016 0.254)
							(mid 0 0.3556)
							(end -0.1016 0.254)
						)
						(xy -0.1016 -0.3556) (xy 0.1016 -0.3556)
					)
					(width 0)
					(fill yes)
				)
			)
		)
		(pad "38" smd custom
			(at -0.999998 -2.4511 270)
			(size 0.0508 0.0508)
			(layers "F.Cu" "F.Mask" "F.Paste")
			(net "Net_266")
			(options
				(clearance outline)
				(anchor circle)
			)
			(primitives
				(gr_poly
					(pts
						(arc
							(start 0.1016 0.254)
							(mid 0 0.3556)
							(end -0.1016 0.254)
						)
						(xy -0.1016 -0.3556) (xy 0.1016 -0.3556)
					)
					(width 0)
					(fill yes)
				)
			)
		)
		(pad "39" smd custom
			(at -1.400048 -2.4511 270)
			(size 0.0508 0.0508)
			(layers "F.Cu" "F.Mask" "F.Paste")
			(net "VR_PVCCIO_CPU1_VDD")
			(options
				(clearance outline)
				(anchor circle)
			)
			(primitives
				(gr_poly
					(pts
						(arc
							(start 0.1016 0.254)
							(mid 0 0.3556)
							(end -0.1016 0.254)
						)
						(xy -0.1016 -0.3556) (xy 0.1016 -0.3556)
					)
					(width 0)
					(fill yes)
				)
			)
		)
		(pad "40" smd custom
			(at -1.800098 -2.4511 270)
			(size 0.0508 0.0508)
			(layers "F.Cu" "F.Mask" "F.Paste")
			(net "VR_PVCCIO_CPU1_VD12")
			(options
				(clearance outline)
				(anchor circle)
			)
			(primitives
				(gr_poly
					(pts
						(arc
							(start 0.1016 0.254)
							(mid 0 0.3556)
							(end -0.1016 0.254)
						)
						(xy -0.1016 -0.3556) (xy 0.1016 -0.3556)
					)
					(width 0)
					(fill yes)
				)
			)
		)
		(pad "41" smd rect
			(at 0 0 270)
			(size 3.683 3.683)
			(layers "F.Cu" "F.Mask" "F.Paste")
			(net "GND")
		)
	)
)
